(kicad_pcb
	(version 20260206)
	(generator "pcbnew")
	(generator_version "10.0")
	(general
		(thickness 1.6)
		(legacy_teardrops no)
	)
	(paper "A4")
	(title_block
		(title "pdpb — Lightning_PDPB_BRD.brd")
		(comment 1 "Lightning (Wiwynn / Facebook NVMe JBOF) / footprints 889-896 of 1140")
	)
	(layers
		(0 "F.Cu" signal "TOP")
		(4 "In1.Cu" signal "L2GND")
		(6 "In2.Cu" signal "L3")
		(8 "In3.Cu" signal "L4VCC")
		(10 "In4.Cu" signal "L5VCC")
		(12 "In5.Cu" signal "L6")
		(14 "In6.Cu" signal "L7GND")
		(2 "B.Cu" signal "BOTTOM")
		(9 "F.Adhes" user "F.Adhesive")
		(11 "B.Adhes" user "B.Adhesive")
		(13 "F.Paste" user "Package Geometry/Pastemask Top")
		(15 "B.Paste" user "Package Geometry/Pastemask Bottom")
		(5 "F.SilkS" user "Ref Des/Silkscreen Top")
		(7 "B.SilkS" user "Ref Des/Silkscreen Bottom")
		(1 "F.Mask" user "Board Geometry/Soldermask Top")
		(3 "B.Mask" user "Board Geometry/Soldermask Bottom")
		(17 "Dwgs.User" user "User.Drawings")
		(19 "Cmts.User" user "User.Comments")
		(21 "Eco1.User" user "User.Eco1")
		(23 "Eco2.User" user "User.Eco2")
		(25 "Edge.Cuts" user "Board Geometry/Outline")
		(27 "Margin" user)
		(31 "F.CrtYd" user "Package Geometry/Place Bound Top")
		(29 "B.CrtYd" user "Package Geometry/Place Bound Bottom")
		(35 "F.Fab" user "Ref Des/Assembly Top")
		(33 "B.Fab" user "Ref Des/Assembly Bottom")
	)
	(footprint ""
		(layer "F.Cu")
		(at 22.352 -265.303 180)
		(property "Reference" "R9862"
			(at 0 0 180)
			(layer "F.SilkS")
			(hide yes)
			(effects
				(font
					(size 1.27 1.27)
				)
			)
		)
		(property "Value" "0R2J-2-GP"
			(at 0.064008 -3.993896 180)
			(unlocked yes)
			(layer "F.Fab")
			(hide yes)
			(effects
				(font
					(size 1.016 1.016)
					(thickness 0.1524)
				)
			)
		)
		(property "Device Type" "R402H16"
			(at 0.064008 -5.517896 180)
			(unlocked yes)
			(layer "F.Fab")
			(hide yes)
			(effects
				(font
					(size 1.016 1.016)
					(thickness 0.1524)
				)
			)
		)
		(duplicate_pad_numbers_are_jumpers no)
		(fp_line
			(start 0.508 -0.9398)
			(end -0.508 -0.9398)
			(stroke
				(width 0.1524)
				(type default)
			)
			(layer "F.SilkS")
		)
		(fp_line
			(start -0.508 -0.9398)
			(end -0.508 0.9398)
			(stroke
				(width 0.1524)
				(type default)
			)
			(layer "F.SilkS")
		)
		(fp_rect
			(start -0.508 0.9398)
			(end 0.508 -0.9398)
			(stroke
				(width 0)
				(type default)
			)
			(fill no)
			(layer "F.CrtYd")
		)
		(fp_rect
			(start -0.508 0.9398)
			(end 0.508 -0.9398)
			(stroke
				(width 0)
				(type default)
			)
			(fill no)
			(layer "F.Fab")
		)
		(pad "1" smd custom
			(at 0 -0.4445 180)
			(size 0.1397 0.1397)
			(layers "F.Cu" "F.Mask" "F.Paste")
			(net "ATTN_LED_DR12_R")
			(options
				(clearance outline)
				(anchor circle)
			)
			(primitives
				(gr_poly
					(pts
						(arc
							(start -0.1778 -0.2794)
							(mid -0.249642 -0.249642)
							(end -0.2794 -0.1778)
						)
						(arc
							(start -0.2794 0.1778)
							(mid -0.249642 0.249642)
							(end -0.1778 0.2794)
						)
						(arc
							(start 0.1778 0.2794)
							(mid 0.249642 0.249642)
							(end 0.2794 0.1778)
						)
						(arc
							(start 0.2794 -0.1778)
							(mid 0.249642 -0.249642)
							(end 0.1778 -0.2794)
						)
					)
					(width 0)
					(fill yes)
				)
			)
		)
		(pad "2" smd custom
			(at 0 0.4445 180)
			(size 0.1397 0.1397)
			(layers "F.Cu" "F.Mask" "F.Paste")
			(net "ATTN_LED_DR12_N")
			(options
				(clearance outline)
				(anchor circle)
			)
			(primitives
				(gr_poly
					(pts
						(arc
							(start -0.1778 -0.2794)
							(mid -0.249642 -0.249642)
							(end -0.2794 -0.1778)
						)
						(arc
							(start -0.2794 0.1778)
							(mid -0.249642 0.249642)
							(end -0.1778 0.2794)
						)
						(arc
							(start 0.1778 0.2794)
							(mid 0.249642 0.249642)
							(end 0.2794 0.1778)
						)
						(arc
							(start 0.2794 -0.1778)
							(mid 0.249642 -0.249642)
							(end 0.1778 -0.2794)
						)
					)
					(width 0)
					(fill yes)
				)
			)
		)
	)
	(footprint ""
		(layer "F.Cu")
		(at 99.06 -86.614 -90)
		(property "Reference" "R9589"
			(at 0 0 270)
			(layer "F.SilkS")
			(hide yes)
			(effects
				(font
					(size 1.27 1.27)
				)
			)
		)
		(property "Value" "4K7R2J-2-GP"
			(at 0.064008 -3.993896 270)
			(unlocked yes)
			(layer "F.Fab")
			(hide yes)
			(effects
				(font
					(size 1.016 1.016)
					(thickness 0.1524)
				)
			)
		)
		(property "Device Type" "R402H16"
			(at 0.064008 -5.517896 270)
			(unlocked yes)
			(layer "F.Fab")
			(hide yes)
			(effects
				(font
					(size 1.016 1.016)
					(thickness 0.1524)
				)
			)
		)
		(duplicate_pad_numbers_are_jumpers no)
		(fp_line
			(start -0.508 -0.9398)
			(end -0.508 0.9398)
			(stroke
				(width 0.1524)
				(type default)
			)
			(layer "F.SilkS")
		)
		(fp_line
			(start 0.508 -0.9398)
			(end -0.508 -0.9398)
			(stroke
				(width 0.1524)
				(type default)
			)
			(layer "F.SilkS")
		)
		(fp_rect
			(start -0.508 0.9398)
			(end 0.508 -0.9398)
			(stroke
				(width 0)
				(type default)
			)
			(fill no)
			(layer "F.CrtYd")
		)
		(fp_rect
			(start -0.508 0.9398)
			(end 0.508 -0.9398)
			(stroke
				(width 0)
				(type default)
			)
			(fill no)
			(layer "F.Fab")
		)
		(pad "1" smd custom
			(at 0 -0.4445 270)
			(size 0.1397 0.1397)
			(layers "F.Cu" "F.Mask" "F.Paste")
			(net "P3V3")
			(options
				(clearance outline)
				(anchor circle)
			)
			(primitives
				(gr_poly
					(pts
						(arc
							(start -0.1778 -0.2794)
							(mid -0.249642 -0.249642)
							(end -0.2794 -0.1778)
						)
						(arc
							(start -0.2794 0.1778)
							(mid -0.249642 0.249642)
							(end -0.1778 0.2794)
						)
						(arc
							(start 0.1778 0.2794)
							(mid 0.249642 0.249642)
							(end 0.2794 0.1778)
						)
						(arc
							(start 0.2794 -0.1778)
							(mid 0.249642 -0.249642)
							(end 0.1778 -0.2794)
						)
					)
					(width 0)
					(fill yes)
				)
			)
		)
		(pad "2" smd custom
			(at 0 0.4445 270)
			(size 0.1397 0.1397)
			(layers "F.Cu" "F.Mask" "F.Paste")
			(net "SSD14_CLK0_OE_N")
			(options
				(clearance outline)
				(anchor circle)
			)
			(primitives
				(gr_poly
					(pts
						(arc
							(start -0.1778 -0.2794)
							(mid -0.249642 -0.249642)
							(end -0.2794 -0.1778)
						)
						(arc
							(start -0.2794 0.1778)
							(mid -0.249642 0.249642)
							(end -0.1778 0.2794)
						)
						(arc
							(start 0.1778 0.2794)
							(mid 0.249642 0.249642)
							(end 0.2794 0.1778)
						)
						(arc
							(start 0.2794 -0.1778)
							(mid 0.249642 -0.249642)
							(end 0.1778 -0.2794)
						)
					)
					(width 0)
					(fill yes)
				)
			)
		)
	)
	(footprint ""
		(layer "F.Cu")
		(at 208.915 -439.42 90)
		(property "Reference" "PG4"
			(at 0 0 90)
			(layer "F.SilkS")
			(hide yes)
			(effects
				(font
					(size 1.27 1.27)
				)
			)
		)
		(property "Value" "GAP-CLOSE-PWR-4-GP"
			(at -2.4638 -0.5461 90)
			(unlocked yes)
			(layer "F.Fab")
			(hide yes)
			(effects
				(font
					(size 1.016 1.016)
					(thickness 0.1524)
				)
			)
		)
		(property "Device Type" "GAP-CLOSE-PWR-4"
			(at -2.4638 -2.0701 90)
			(unlocked yes)
			(layer "F.Fab")
			(hide yes)
			(effects
				(font
					(size 1.016 1.016)
					(thickness 0.1524)
				)
			)
		)
		(duplicate_pad_numbers_are_jumpers no)
		(fp_rect
			(start -0.2794 0.254)
			(end 0.2794 -0.254)
			(stroke
				(width 0)
				(type default)
			)
			(fill no)
			(layer "F.CrtYd")
		)
		(fp_rect
			(start -0.2794 0.254)
			(end 0.2794 -0.254)
			(stroke
				(width 0)
				(type default)
			)
			(fill no)
			(layer "F.Fab")
		)
		(pad "1" smd rect
			(at -0.0635 0 90)
			(size 0.1778 0.254)
			(layers "F.Cu" "F.Mask" "F.Paste")
			(net "P3V3_OUT")
		)
		(pad "2" smd rect
			(at 0.0635 0 90)
			(size 0.1778 0.254)
			(layers "F.Cu" "F.Mask" "F.Paste")
			(net "P3V3_CC")
		)
	)
	(footprint ""
		(layer "F.Cu")
		(at 22.14245 -198.95185 90)
		(property "Reference" "R9833"
			(at 0 0 90)
			(layer "F.SilkS")
			(hide yes)
			(effects
				(font
					(size 1.27 1.27)
				)
			)
		)
		(property "Value" "1KR2J-1-GP"
			(at 0.064008 -3.993896 90)
			(unlocked yes)
			(layer "F.Fab")
			(hide yes)
			(effects
				(font
					(size 1.016 1.016)
					(thickness 0.1524)
				)
			)
		)
		(property "Device Type" "R402H16"
			(at 0.064008 -5.517896 90)
			(unlocked yes)
			(layer "F.Fab")
			(hide yes)
			(effects
				(font
					(size 1.016 1.016)
					(thickness 0.1524)
				)
			)
		)
		(duplicate_pad_numbers_are_jumpers no)
		(fp_line
			(start 0.508 -0.9398)
			(end -0.508 -0.9398)
			(stroke
				(width 0.1524)
				(type default)
			)
			(layer "F.SilkS")
		)
		(fp_line
			(start -0.508 -0.9398)
			(end -0.508 0.9398)
			(stroke
				(width 0.1524)
				(type default)
			)
			(layer "F.SilkS")
		)
		(fp_rect
			(start -0.508 0.9398)
			(end 0.508 -0.9398)
			(stroke
				(width 0)
				(type default)
			)
			(fill no)
			(layer "F.CrtYd")
		)
		(fp_rect
			(start -0.508 0.9398)
			(end 0.508 -0.9398)
			(stroke
				(width 0)
				(type default)
			)
			(fill no)
			(layer "F.Fab")
		)
		(pad "1" smd custom
			(at 0 -0.4445 90)
			(size 0.1397 0.1397)
			(layers "F.Cu" "F.Mask" "F.Paste")
			(net "SSD8_PWREN")
			(options
				(clearance outline)
				(anchor circle)
			)
			(primitives
				(gr_poly
					(pts
						(arc
							(start -0.1778 -0.2794)
							(mid -0.249642 -0.249642)
							(end -0.2794 -0.1778)
						)
						(arc
							(start -0.2794 0.1778)
							(mid -0.249642 0.249642)
							(end -0.1778 0.2794)
						)
						(arc
							(start 0.1778 0.2794)
							(mid 0.249642 0.249642)
							(end 0.2794 0.1778)
						)
						(arc
							(start 0.2794 -0.1778)
							(mid 0.249642 -0.249642)
							(end 0.1778 -0.2794)
						)
					)
					(width 0)
					(fill yes)
				)
			)
		)
		(pad "2" smd custom
			(at 0 0.4445 90)
			(size 0.1397 0.1397)
			(layers "F.Cu" "F.Mask" "F.Paste")
			(net "SSD8_PWREN_R")
			(options
				(clearance outline)
				(anchor circle)
			)
			(primitives
				(gr_poly
					(pts
						(arc
							(start -0.1778 -0.2794)
							(mid -0.249642 -0.249642)
							(end -0.2794 -0.1778)
						)
						(arc
							(start -0.2794 0.1778)
							(mid -0.249642 0.249642)
							(end -0.1778 0.2794)
						)
						(arc
							(start 0.1778 0.2794)
							(mid 0.249642 0.249642)
							(end 0.2794 0.1778)
						)
						(arc
							(start 0.2794 -0.1778)
							(mid 0.249642 -0.249642)
							(end 0.1778 -0.2794)
						)
					)
					(width 0)
					(fill yes)
				)
			)
		)
	)
	(footprint ""
		(layer "F.Cu")
		(at 37.6936 -109.8804)
		(property "Reference" "R581"
			(at 0 0 0)
			(layer "F.SilkS")
			(hide yes)
			(effects
				(font
					(size 1.27 1.27)
				)
			)
		)
		(property "Value" "300KR2F-GP"
			(at 0.064008 -3.993896 0)
			(unlocked yes)
			(layer "F.Fab")
			(hide yes)
			(effects
				(font
					(size 1.016 1.016)
					(thickness 0.1524)
				)
			)
		)
		(property "Device Type" "R402H16"
			(at 0.064008 -5.517896 0)
			(unlocked yes)
			(layer "F.Fab")
			(hide yes)
			(effects
				(font
					(size 1.016 1.016)
					(thickness 0.1524)
				)
			)
		)
		(duplicate_pad_numbers_are_jumpers no)
		(fp_line
			(start -0.508 -0.9398)
			(end -0.508 0.9398)
			(stroke
				(width 0.1524)
				(type default)
			)
			(layer "F.SilkS")
		)
		(fp_line
			(start 0.508 -0.9398)
			(end -0.508 -0.9398)
			(stroke
				(width 0.1524)
				(type default)
			)
			(layer "F.SilkS")
		)
		(fp_rect
			(start -0.508 0.9398)
			(end 0.508 -0.9398)
			(stroke
				(width 0)
				(type default)
			)
			(fill no)
			(layer "F.CrtYd")
		)
		(fp_rect
			(start -0.508 0.9398)
			(end 0.508 -0.9398)
			(stroke
				(width 0)
				(type default)
			)
			(fill no)
			(layer "F.Fab")
		)
		(pad "1" smd custom
			(at 0 -0.4445)
			(size 0.1397 0.1397)
			(layers "F.Cu" "F.Mask" "F.Paste")
			(net "SW_SSD13_N")
			(options
				(clearance outline)
				(anchor circle)
			)
			(primitives
				(gr_poly
					(pts
						(arc
							(start -0.1778 -0.2794)
							(mid -0.249642 -0.249642)
							(end -0.2794 -0.1778)
						)
						(arc
							(start -0.2794 0.1778)
							(mid -0.249642 0.249642)
							(end -0.1778 0.2794)
						)
						(arc
							(start 0.1778 0.2794)
							(mid 0.249642 0.249642)
							(end 0.2794 0.1778)
						)
						(arc
							(start 0.2794 -0.1778)
							(mid 0.249642 -0.249642)
							(end 0.1778 -0.2794)
						)
					)
					(width 0)
					(fill yes)
				)
			)
		)
		(pad "2" smd custom
			(at 0 0.4445)
			(size 0.1397 0.1397)
			(layers "F.Cu" "F.Mask" "F.Paste")
			(net "P12V")
			(options
				(clearance outline)
				(anchor circle)
			)
			(primitives
				(gr_poly
					(pts
						(arc
							(start -0.1778 -0.2794)
							(mid -0.249642 -0.249642)
							(end -0.2794 -0.1778)
						)
						(arc
							(start -0.2794 0.1778)
							(mid -0.249642 0.249642)
							(end -0.1778 0.2794)
						)
						(arc
							(start 0.1778 0.2794)
							(mid 0.249642 0.249642)
							(end 0.2794 0.1778)
						)
						(arc
							(start 0.2794 -0.1778)
							(mid 0.249642 -0.249642)
							(end 0.1778 -0.2794)
						)
					)
					(width 0)
					(fill yes)
				)
			)
		)
	)
	(footprint ""
		(layer "F.Cu")
		(at 87.122 -436.499)
		(property "Reference" "C8893"
			(at 0 0 0)
			(layer "F.SilkS")
			(hide yes)
			(effects
				(font
					(size 1.27 1.27)
				)
			)
		)
		(property "Value" "SC1U10V2KX-7-GP"
			(at 1.1811 -2.7051 0)
			(unlocked yes)
			(layer "F.Fab")
			(hide yes)
			(effects
				(font
					(size 1.016 1.016)
					(thickness 0.1524)
				)
			)
		)
		(property "Device Type" "C402H22"
			(at 1.1811 -4.2291 0)
			(unlocked yes)
			(layer "F.Fab")
			(hide yes)
			(effects
				(font
					(size 1.016 1.016)
					(thickness 0.1524)
				)
			)
		)
		(duplicate_pad_numbers_are_jumpers no)
		(fp_rect
			(start -0.4318 0.9525)
			(end 0.4318 -0.9525)
			(stroke
				(width 0)
				(type default)
			)
			(fill no)
			(layer "F.CrtYd")
		)
		(fp_rect
			(start -0.4318 0.9525)
			(end 0.4318 -0.9525)
			(stroke
				(width 0)
				(type default)
			)
			(fill no)
			(layer "F.Fab")
		)
		(pad "1" smd custom
			(at 0 -0.4445)
			(size 0.1524 0.1524)
			(layers "F.Cu" "F.Mask" "F.Paste")
			(net "VDDA_1")
			(options
				(clearance outline)
				(anchor circle)
			)
			(primitives
				(gr_poly
					(pts
						(arc
							(start 0.3048 -0.2032)
							(mid 0.275042 -0.275042)
							(end 0.2032 -0.3048)
						)
						(arc
							(start -0.2032 -0.3048)
							(mid -0.275042 -0.275042)
							(end -0.3048 -0.2032)
						)
						(arc
							(start -0.3048 0.2032)
							(mid -0.275042 0.275042)
							(end -0.2032 0.3048)
						)
						(arc
							(start 0.2032 0.3048)
							(mid 0.275042 0.275042)
							(end 0.3048 0.2032)
						)
					)
					(width 0)
					(fill yes)
				)
			)
		)
		(pad "2" smd custom
			(at 0 0.4445)
			(size 0.1524 0.1524)
			(layers "F.Cu" "F.Mask" "F.Paste")
			(net "GND")
			(options
				(clearance outline)
				(anchor circle)
			)
			(primitives
				(gr_poly
					(pts
						(arc
							(start 0.3048 -0.2032)
							(mid 0.275042 -0.275042)
							(end 0.2032 -0.3048)
						)
						(arc
							(start -0.2032 -0.3048)
							(mid -0.275042 -0.275042)
							(end -0.3048 -0.2032)
						)
						(arc
							(start -0.3048 0.2032)
							(mid -0.275042 0.275042)
							(end -0.2032 0.3048)
						)
						(arc
							(start 0.2032 0.3048)
							(mid 0.275042 0.275042)
							(end 0.3048 0.2032)
						)
					)
					(width 0)
					(fill yes)
				)
			)
		)
	)
	(footprint ""
		(layer "F.Cu")
		(at 108.966 -434.848)
		(property "Reference" "R118"
			(at 0 0 0)
			(layer "F.SilkS")
			(hide yes)
			(effects
				(font
					(size 1.27 1.27)
				)
			)
		)
		(property "Value" "4K7R2J-2-GP"
			(at 0.064008 -3.993896 0)
			(unlocked yes)
			(layer "F.Fab")
			(hide yes)
			(effects
				(font
					(size 1.016 1.016)
					(thickness 0.1524)
				)
			)
		)
		(property "Device Type" "R402H16"
			(at 0.064008 -5.517896 0)
			(unlocked yes)
			(layer "F.Fab")
			(hide yes)
			(effects
				(font
					(size 1.016 1.016)
					(thickness 0.1524)
				)
			)
		)
		(duplicate_pad_numbers_are_jumpers no)
		(fp_line
			(start -0.508 -0.9398)
			(end -0.508 0.9398)
			(stroke
				(width 0.1524)
				(type default)
			)
			(layer "F.SilkS")
		)
		(fp_line
			(start 0.508 -0.9398)
			(end -0.508 -0.9398)
			(stroke
				(width 0.1524)
				(type default)
			)
			(layer "F.SilkS")
		)
		(fp_rect
			(start -0.508 0.9398)
			(end 0.508 -0.9398)
			(stroke
				(width 0)
				(type default)
			)
			(fill no)
			(layer "F.CrtYd")
		)
		(fp_rect
			(start -0.508 0.9398)
			(end 0.508 -0.9398)
			(stroke
				(width 0)
				(type default)
			)
			(fill no)
			(layer "F.Fab")
		)
		(pad "1" smd custom
			(at 0 -0.4445)
			(size 0.1397 0.1397)
			(layers "F.Cu" "F.Mask" "F.Paste")
			(net "P3V3")
			(options
				(clearance outline)
				(anchor circle)
			)
			(primitives
				(gr_poly
					(pts
						(arc
							(start -0.1778 -0.2794)
							(mid -0.249642 -0.249642)
							(end -0.2794 -0.1778)
						)
						(arc
							(start -0.2794 0.1778)
							(mid -0.249642 0.249642)
							(end -0.1778 0.2794)
						)
						(arc
							(start 0.1778 0.2794)
							(mid 0.249642 0.249642)
							(end 0.2794 0.1778)
						)
						(arc
							(start 0.2794 -0.1778)
							(mid 0.249642 -0.249642)
							(end 0.1778 -0.2794)
						)
					)
					(width 0)
					(fill yes)
				)
			)
		)
		(pad "2" smd custom
			(at 0 0.4445)
			(size 0.1397 0.1397)
			(layers "F.Cu" "F.Mask" "F.Paste")
			(net "SSD_PRSNT_NET0")
			(options
				(clearance outline)
				(anchor circle)
			)
			(primitives
				(gr_poly
					(pts
						(arc
							(start -0.1778 -0.2794)
							(mid -0.249642 -0.249642)
							(end -0.2794 -0.1778)
						)
						(arc
							(start -0.2794 0.1778)
							(mid -0.249642 0.249642)
							(end -0.1778 0.2794)
						)
						(arc
							(start 0.1778 0.2794)
							(mid 0.249642 0.249642)
							(end 0.2794 0.1778)
						)
						(arc
							(start 0.2794 -0.1778)
							(mid 0.249642 -0.249642)
							(end 0.1778 -0.2794)
						)
					)
					(width 0)
					(fill yes)
				)
			)
		)
	)
	(footprint ""
		(layer "F.Cu")
		(at 43.0784 -93.5482)
		(property "Reference" "R9242"
			(at 0 0 0)
			(layer "F.SilkS")
			(hide yes)
			(effects
				(font
					(size 1.27 1.27)
				)
			)
		)
		(property "Value" "2R2010F-GP"
			(at 0.0762 -4.5466 0)
			(unlocked yes)
			(layer "F.Fab")
			(hide yes)
			(effects
				(font
					(size 1.016 1.016)
					(thickness 0.1524)
				)
			)
		)
		(property "Device Type" "R2010H26"
			(at 0.0762 -6.1468 0)
			(unlocked yes)
			(layer "F.Fab")
			(hide yes)
			(effects
				(font
					(size 1.016 1.016)
					(thickness 0.1524)
				)
			)
		)
		(duplicate_pad_numbers_are_jumpers no)
		(fp_line
			(start -3.302 -1.651)
			(end -3.302 1.651)
			(stroke
				(width 0.1524)
				(type default)
			)
			(layer "F.SilkS")
		)
		(fp_line
			(start -3.302 1.651)
			(end 3.302 1.651)
			(stroke
				(width 0.1524)
				(type default)
			)
			(layer "F.SilkS")
		)
		(fp_line
			(start 3.302 -1.651)
			(end -3.302 -1.651)
			(stroke
				(width 0.1524)
				(type default)
			)
			(layer "F.SilkS")
		)
		(fp_line
			(start 3.302 1.651)
			(end 3.302 -1.651)
			(stroke
				(width 0.1524)
				(type default)
			)
			(layer "F.SilkS")
		)
		(fp_rect
			(start -3.3782 1.7272)
			(end 3.3782 -1.7272)
			(stroke
				(width 0)
				(type default)
			)
			(fill no)
			(layer "F.CrtYd")
		)
		(fp_poly
			(pts
				(xy 3.3782 -1.7272) (xy -3.3782 -1.7272) (xy -3.3782 1.7272) (xy 3.3782 1.7272)
			)
			(stroke
				(width 0)
				(type default)
			)
			(fill no)
			(layer "F.Fab")
		)
		(pad "1" smd rect
			(at -2.3495 0)
			(size 1.143 2.794)
			(layers "F.Cu" "F.Mask" "F.Paste")
			(net "P12V_SSD9")
		)
		(pad "2" smd rect
			(at 2.3495 0)
			(size 1.143 2.794)
			(layers "F.Cu" "F.Mask" "F.Paste")
			(net "12V_PRECH_SSD9")
		)
	)
)
